# BASEBOARD_FAB2 (Tioga Pass) — schematic netlist excerpt (pin names and nets, part order shuffled) for the footprints in the layout excerpt that follows; sources: Cadence DE-HDL packaged netlist, KiCad conversion of Wiwynn_Tioga_Pass_MB.brd

EU7A5  PXM1310B  IC  pkg QFN  page 218
  BPWM1  = NC
  DNC(0)  = NC
  APWM3  = NC
  APWM2  = VR_PVDDQ_DEF_PWM2
  APWM1  = VR_PVDDQ_DEF_PWM1
  SDA  = SMB_VR_STBY_LVC3_SDA
  SCL  = SMB_VR_STBY_LVC3_SCL
  RESET_N  = NC
  AVRRDY  = PWRGD_PVDDQ_DEF_R
  AVREN  = VR_PVDDQ_DEF_VREN
  VRHOT_N  = IRQ_PVDDQ_DEF_VRHOT_LVT3_R_N
  PINALRT_N  = NC
  MP0  = PU_VR_PVDDQ_DEF_FAULT1
  MP1  = TP_PVDDQ_DEF_MP1
  VCLK  = SVID_CLK_PVDDQ_DEF
  VDIO  = SVID_VDIO_PVDDQ_DEF
  VALRT_N  = SVID_ALERT_PVDDQ_DEF
  MP2  = TP_PVDDQ_DEF_MP2
  AVSEN  = VR_PVDDQ_DEF_AVSP
  AVREF  = VSENSE_PVDDQ_DEF_N
  AIREF1  = VR_PVDDQ_DEF_AIREF1
  AISEN1  = ISENSE_PVDDQ_DEF_PH1_IMON
  AIREF2  = VR_PVDDQ_DEF_AIREF2
  AISEN2  = ISENSE_PVDDQ_DEF_PH2_IMON
  AIREF3  = NC
  AISEN3  = NC
  GND  = GND
  DNC(1)  = NC
  BVSEN  = NC
  BVREF  = NC
  BIREF1  = NC
  BISEN1  = GND
  XADDR2  = VR_PVDDQ_DEF_XADDR2
  BTSEN  = NC
  ATSEN  = A_TSENSE_PVDDQ_DEF
  XADDR1  = VR_PVDDQ_DEF_XADDR1
  VINSEN  = VR_PVDDQ_DEF_VINSEN
  IINSEN  = VR_PVDDQ_DEF_AIINSEN
  VDD  = VR_PVDDQ_DEF_VDD
  VD12  = VR_PVDDQ_DEF_VD12
  THPAD  = GND

(kicad_pcb
	(version 20260206)
	(generator "pcbnew")
	(generator_version "10.0")
	(general
		(thickness 1.6)
		(legacy_teardrops no)
	)
	(paper "A4")
	(title_block
		(title "Wiwynn_Tioga_Pass_MB.brd")
		(comment 1 "Tioga Pass / footprint 1253 of 4770 (EU7A5), pads 18-34 of 41")
	)
	(layers
		(0 "F.Cu" signal "TOP")
		(4 "In1.Cu" signal "L2GND")
		(6 "In2.Cu" signal "L3")
		(8 "In3.Cu" signal "L4GND")
		(10 "In4.Cu" signal "L5")
		(12 "In5.Cu" signal "L6GND")
		(14 "In6.Cu" signal "L7VCC")
		(16 "In7.Cu" signal "L8VCC")
		(18 "In8.Cu" signal "L9GND")
		(20 "In9.Cu" signal "L10")
		(22 "In10.Cu" signal "L11GND")
		(24 "In11.Cu" signal "L12")
		(26 "In12.Cu" signal "L13GND")
		(2 "B.Cu" signal "BOTTOM")
		(9 "F.Adhes" user "F.Adhesive")
		(11 "B.Adhes" user "B.Adhesive")
		(13 "F.Paste" user "Package Geometry/Pastemask Top")
		(15 "B.Paste" user "Package Geometry/Pastemask Bottom")
		(5 "F.SilkS" user "Ref Des/Silkscreen Top")
		(7 "B.SilkS" user "Ref Des/Silkscreen Bottom")
		(1 "F.Mask" user "Board Geometry/Soldermask Top")
		(3 "B.Mask" user "Board Geometry/Soldermask Bottom")
		(17 "Dwgs.User" user "User.Drawings")
		(19 "Cmts.User" user "User.Comments")
		(21 "Eco1.User" user "User.Eco1")
		(23 "Eco2.User" user "User.Eco2")
		(25 "Edge.Cuts" user "Board Geometry/Outline")
		(27 "Margin" user)
		(31 "F.CrtYd" user "Package Geometry/Place Bound Top")
		(29 "B.CrtYd" user "Package Geometry/Place Bound Bottom")
		(35 "F.Fab" user "Ref Des/Assembly Top")
		(33 "B.Fab" user "Ref Des/Assembly Bottom")
	)
	(footprint ""
		(layer "F.Cu")
		(at 359.29824 -138.16457 90)
		(property "Reference" "EU7A5"
			(at -1.51257 -3.29057 90)
			(unlocked yes)
			(layer "F.SilkS")
			(effects
				(font
					(size 0.7874 0.5842)
					(thickness 0.1524)
				)
				(justify left)
			)
		)
		(property "Value" ""
			(at 0 0 90)
			(layer "F.Fab")
			(effects
				(font
					(size 1.27 1.27)
				)
			)
		)
		(duplicate_pad_numbers_are_jumpers no)
		(pad "18" smd custom
			(at 0.999998 2.4511 90)
			(size 0.0508 0.0508)
			(layers "F.Cu" "F.Mask" "F.Paste")
			(net "TP_PVDDQ_DEF_MP2")
			(options
				(clearance outline)
				(anchor circle)
			)
			(primitives
				(gr_poly
					(pts
						(arc
							(start -0.1016 -0.254)
							(mid 0 -0.3556)
							(end 0.1016 -0.254)
						)
						(xy 0.1016 0.3556) (xy -0.1016 0.3556)
					)
					(width 0)
					(fill yes)
				)
			)
		)
		(pad "19" smd custom
			(at 1.400048 2.4511 90)
			(size 0.0508 0.0508)
			(layers "F.Cu" "F.Mask" "F.Paste")
			(net "VR_PVDDQ_DEF_AVSP")
			(options
				(clearance outline)
				(anchor circle)
			)
			(primitives
				(gr_poly
					(pts
						(arc
							(start -0.1016 -0.254)
							(mid 0 -0.3556)
							(end 0.1016 -0.254)
						)
						(xy 0.1016 0.3556) (xy -0.1016 0.3556)
					)
					(width 0)
					(fill yes)
				)
			)
		)
		(pad "20" smd custom
			(at 1.800098 2.4511 90)
			(size 0.0508 0.0508)
			(layers "F.Cu" "F.Mask" "F.Paste")
			(net "VSENSE_PVDDQ_DEF_N")
			(options
				(clearance outline)
				(anchor circle)
			)
			(primitives
				(gr_poly
					(pts
						(arc
							(start -0.1016 -0.254)
							(mid 0 -0.3556)
							(end 0.1016 -0.254)
						)
						(xy 0.1016 0.3556) (xy -0.1016 0.3556)
					)
					(width 0)
					(fill yes)
				)
			)
		)
		(pad "21" smd custom
			(at 2.4511 1.800098 90)
			(size 0.0508 0.0508)
			(layers "F.Cu" "F.Mask" "F.Paste")
			(net "VR_PVDDQ_DEF_AIREF1")
			(options
				(clearance outline)
				(anchor circle)
			)
			(primitives
				(gr_poly
					(pts
						(arc
							(start -0.254 0.1016)
							(mid -0.3556 0)
							(end -0.254 -0.1016)
						)
						(xy 0.3556 -0.1016) (xy 0.3556 0.1016)
					)
					(width 0)
					(fill yes)
				)
			)
		)
		(pad "22" smd custom
			(at 2.4511 1.400048 90)
			(size 0.0508 0.0508)
			(layers "F.Cu" "F.Mask" "F.Paste")
			(net "ISENSE_PVDDQ_DEF_PH1_IMON")
			(options
				(clearance outline)
				(anchor circle)
			)
			(primitives
				(gr_poly
					(pts
						(arc
							(start -0.254 0.1016)
							(mid -0.3556 0)
							(end -0.254 -0.1016)
						)
						(xy 0.3556 -0.1016) (xy 0.3556 0.1016)
					)
					(width 0)
					(fill yes)
				)
			)
		)
		(pad "23" smd custom
			(at 2.4511 0.999998 90)
			(size 0.0508 0.0508)
			(layers "F.Cu" "F.Mask" "F.Paste")
			(net "VR_PVDDQ_DEF_AIREF2")
			(options
				(clearance outline)
				(anchor circle)
			)
			(primitives
				(gr_poly
					(pts
						(arc
							(start -0.254 0.1016)
							(mid -0.3556 0)
							(end -0.254 -0.1016)
						)
						(xy 0.3556 -0.1016) (xy 0.3556 0.1016)
					)
					(width 0)
					(fill yes)
				)
			)
		)
		(pad "24" smd custom
			(at 2.4511 0.599948 90)
			(size 0.0508 0.0508)
			(layers "F.Cu" "F.Mask" "F.Paste")
			(net "ISENSE_PVDDQ_DEF_PH2_IMON")
			(options
				(clearance outline)
				(anchor circle)
			)
			(primitives
				(gr_poly
					(pts
						(arc
							(start -0.254 0.1016)
							(mid -0.3556 0)
							(end -0.254 -0.1016)
						)
						(xy 0.3556 -0.1016) (xy 0.3556 0.1016)
					)
					(width 0)
					(fill yes)
				)
			)
		)
		(pad "25" smd custom
			(at 2.4511 0.199898 90)
			(size 0.0508 0.0508)
			(layers "F.Cu" "F.Mask" "F.Paste")
			(net "Net_244")
			(options
				(clearance outline)
				(anchor circle)
			)
			(primitives
				(gr_poly
					(pts
						(arc
							(start -0.254 0.1016)
							(mid -0.3556 0)
							(end -0.254 -0.1016)
						)
						(xy 0.3556 -0.1016) (xy 0.3556 0.1016)
					)
					(width 0)
					(fill yes)
				)
			)
		)
		(pad "26" smd custom
			(at 2.4511 -0.199898 90)
			(size 0.0508 0.0508)
			(layers "F.Cu" "F.Mask" "F.Paste")
			(net "Net_243")
			(options
				(clearance outline)
				(anchor circle)
			)
			(primitives
				(gr_poly
					(pts
						(arc
							(start -0.254 0.1016)
							(mid -0.3556 0)
							(end -0.254 -0.1016)
						)
						(xy 0.3556 -0.1016) (xy 0.3556 0.1016)
					)
					(width 0)
					(fill yes)
				)
			)
		)
		(pad "27" smd custom
			(at 2.4511 -0.599948 90)
			(size 0.0508 0.0508)
			(layers "F.Cu" "F.Mask" "F.Paste")
			(net "GND")
			(options
				(clearance outline)
				(anchor circle)
			)
			(primitives
				(gr_poly
					(pts
						(arc
							(start -0.254 0.1016)
							(mid -0.3556 0)
							(end -0.254 -0.1016)
						)
						(xy 0.3556 -0.1016) (xy 0.3556 0.1016)
					)
					(width 0)
					(fill yes)
				)
			)
		)
		(pad "28" smd custom
			(at 2.4511 -0.999998 90)
			(size 0.0508 0.0508)
			(layers "F.Cu" "F.Mask" "F.Paste")
			(net "Net_348")
			(options
				(clearance outline)
				(anchor circle)
			)
			(primitives
				(gr_poly
					(pts
						(arc
							(start -0.254 0.1016)
							(mid -0.3556 0)
							(end -0.254 -0.1016)
						)
						(xy 0.3556 -0.1016) (xy 0.3556 0.1016)
					)
					(width 0)
					(fill yes)
				)
			)
		)
		(pad "29" smd custom
			(at 2.4511 -1.400048 90)
			(size 0.0508 0.0508)
			(layers "F.Cu" "F.Mask" "F.Paste")
			(net "Net_229")
			(options
				(clearance outline)
				(anchor circle)
			)
			(primitives
				(gr_poly
					(pts
						(arc
							(start -0.254 0.1016)
							(mid -0.3556 0)
							(end -0.254 -0.1016)
						)
						(xy 0.3556 -0.1016) (xy 0.3556 0.1016)
					)
					(width 0)
					(fill yes)
				)
			)
		)
		(pad "30" smd custom
			(at 2.4511 -1.800098 90)
			(size 0.0508 0.0508)
			(layers "F.Cu" "F.Mask" "F.Paste")
			(net "Net_228")
			(options
				(clearance outline)
				(anchor circle)
			)
			(primitives
				(gr_poly
					(pts
						(arc
							(start -0.254 0.1016)
							(mid -0.3556 0)
							(end -0.254 -0.1016)
						)
						(xy 0.3556 -0.1016) (xy 0.3556 0.1016)
					)
					(width 0)
					(fill yes)
				)
			)
		)
		(pad "31" smd custom
			(at 1.800098 -2.4511 90)
			(size 0.0508 0.0508)
			(layers "F.Cu" "F.Mask" "F.Paste")
			(net "Net_226")
			(options
				(clearance outline)
				(anchor circle)
			)
			(primitives
				(gr_poly
					(pts
						(arc
							(start 0.1016 0.254)
							(mid 0 0.3556)
							(end -0.1016 0.254)
						)
						(xy -0.1016 -0.3556) (xy 0.1016 -0.3556)
					)
					(width 0)
					(fill yes)
				)
			)
		)
		(pad "32" smd custom
			(at 1.400048 -2.4511 90)
			(size 0.0508 0.0508)
			(layers "F.Cu" "F.Mask" "F.Paste")
			(net "GND")
			(options
				(clearance outline)
				(anchor circle)
			)
			(primitives
				(gr_poly
					(pts
						(arc
							(start 0.1016 0.254)
							(mid 0 0.3556)
							(end -0.1016 0.254)
						)
						(xy -0.1016 -0.3556) (xy 0.1016 -0.3556)
					)
					(width 0)
					(fill yes)
				)
			)
		)
		(pad "33" smd custom
			(at 0.999998 -2.4511 90)
			(size 0.0508 0.0508)
			(layers "F.Cu" "F.Mask" "F.Paste")
			(net "VR_PVDDQ_DEF_XADDR2")
			(options
				(clearance outline)
				(anchor circle)
			)
			(primitives
				(gr_poly
					(pts
						(arc
							(start 0.1016 0.254)
							(mid 0 0.3556)
							(end -0.1016 0.254)
						)
						(xy -0.1016 -0.3556) (xy 0.1016 -0.3556)
					)
					(width 0)
					(fill yes)
				)
			)
		)
		(pad "34" smd custom
			(at 0.599948 -2.4511 90)
			(size 0.0508 0.0508)
			(layers "F.Cu" "F.Mask" "F.Paste")
			(net "Net_227")
			(options
				(clearance outline)
				(anchor circle)
			)
			(primitives
				(gr_poly
					(pts
						(arc
							(start 0.1016 0.254)
							(mid 0 0.3556)
							(end -0.1016 0.254)
						)
						(xy -0.1016 -0.3556) (xy 0.1016 -0.3556)
					)
					(width 0)
					(fill yes)
				)
			)
		)
	)
)
